# discovery-power-board-v1-revB — 201842-1040.kicad_mod (kicad-footprint)
(module 201842-1040 (layer F.Cu) 
  (fp_text reference REF** (at 2.02438 -10.6299) (layer F.SilkS)
    (effects (font (size 1 1) (thickness 0.15)))
  )
  (fp_text value 201842-1040 (at 5.24256 1.31826) (layer F.Fab)
    (effects (font (size 1 1) (thickness 0.15)))
  )
  (fp_line (start 0 0) (end 31.86 0) (layer F.SilkS) (width 0.15))
  (fp_line (start 31.86 0) (end 31.86 -9.64) (layer F.SilkS) (width 0.15))
  (fp_line (start 0 -9.64) (end 31.86 -9.64) (layer F.SilkS) (width 0.15))
  (fp_line (start 0 -9.64) (end 0 0) (layer F.SilkS) (width 0.15))
  (fp_line (start -0.3 -9.94) (end 32.16 -9.94) (layer F.CrtYd) (width 0.15))
  (fp_line (start 32.16 -9.94) (end 32.16 0.3) (layer F.CrtYd) (width 0.15))
  (fp_line (start 32.16 0.3) (end -0.3 0.3) (layer F.CrtYd) (width 0.15))
  (fp_line (start -0.3 0.3) (end -0.3 -9.94) (layer F.CrtYd) (width 0.15))
  (pad 4 thru_hole circle (at 4.84 -4.82) (size 5.75 5.75) (drill 4.15) (layers *.Cu *.Mask))
  (pad 3 thru_hole circle (at 12.24 -4.82) (size 5.75 5.75) (drill 4.15) (layers *.Cu *.Mask))
  (pad 2 thru_hole circle (at 19.64 -4.82) (size 5.75 5.75) (drill 4.15) (layers *.Cu *.Mask))
  (pad 1 thru_hole circle (at 27.04 -4.82) (size 5.75 5.75) (drill 4.15) (layers *.Cu *.Mask))
  (pad "" np_thru_hole circle (at 23.34 -8.14) (size 3.25 3.25) (drill 2.5) (layers *.Cu *.Mask))
)
